(kicad_pcb
	(version 20260206)
	(generator "pcbnew")
	(generator_version "10.0")
	(general
		(thickness 1.6)
		(legacy_teardrops no)
	)
	(paper "A4")
	(title_block
		(title "v2-pdb — ms_pdb_v2.brd")
		(comment 1 "Open CloudServer (Microsoft) / footprints 1-5 of 348")
	)
	(layers
		(0 "F.Cu" signal "TOP")
		(4 "In1.Cu" signal "GND")
		(6 "In2.Cu" signal "IN1")
		(8 "In3.Cu" signal "VCC")
		(10 "In4.Cu" signal "VCC1")
		(12 "In5.Cu" signal "IN2")
		(14 "In6.Cu" signal "GND1")
		(2 "B.Cu" signal "BOTTOM")
		(9 "F.Adhes" user "F.Adhesive")
		(11 "B.Adhes" user "B.Adhesive")
		(13 "F.Paste" user "Package Geometry/Pastemask Top")
		(15 "B.Paste" user "Package Geometry/Pastemask Bottom")
		(5 "F.SilkS" user "Ref Des/Silkscreen Top")
		(7 "B.SilkS" user "Ref Des/Silkscreen Bottom")
		(1 "F.Mask" user "Board Geometry/Soldermask Top")
		(3 "B.Mask" user "Board Geometry/Soldermask Bottom")
		(17 "Dwgs.User" user "User.Drawings")
		(19 "Cmts.User" user "User.Comments")
		(21 "Eco1.User" user "User.Eco1")
		(23 "Eco2.User" user "User.Eco2")
		(25 "Edge.Cuts" user "Board Geometry/Outline")
		(27 "Margin" user)
		(31 "F.CrtYd" user "Package Geometry/Place Bound Top")
		(29 "B.CrtYd" user "Package Geometry/Place Bound Bottom")
		(35 "F.Fab" user "Ref Des/Assembly Top")
		(33 "B.Fab" user "Ref Des/Assembly Bottom")
	)
	(footprint ""
		(layer "F.Cu")
		(at 27.639264 -285.429452 -90)
		(property "Reference" "R109"
			(at -1.498854 1.234948 90)
			(unlocked yes)
			(layer "F.SilkS")
			(effects
				(font
					(size 0.7874 0.5842)
					(thickness 0.1524)
				)
				(justify left)
			)
		)
		(property "Value" ""
			(at 0 0 270)
			(layer "F.Fab")
			(effects
				(font
					(size 1.27 1.27)
				)
			)
		)
		(duplicate_pad_numbers_are_jumpers no)
		(fp_line
			(start -0.7874 0.4064)
			(end -0.7874 -0.4064)
			(stroke
				(width 0.1524)
				(type default)
			)
			(layer "F.SilkS")
		)
		(fp_line
			(start 0.7874 0.4064)
			(end -0.7874 0.4064)
			(stroke
				(width 0.1524)
				(type default)
			)
			(layer "F.SilkS")
		)
		(fp_line
			(start -0.7874 -0.4064)
			(end 0.7874 -0.4064)
			(stroke
				(width 0.1524)
				(type default)
			)
			(layer "F.SilkS")
		)
		(fp_line
			(start 0.7874 -0.4064)
			(end 0.7874 0.4064)
			(stroke
				(width 0.1524)
				(type default)
			)
			(layer "F.SilkS")
		)
		(fp_poly
			(pts
				(xy -0.508 0.2794) (xy -0.508 0.2286) (xy -0.635 0.2286) (xy -0.635 -0.254) (xy -0.5334 -0.254)
				(xy -0.5334 -0.2794) (xy 0.5334 -0.2794) (xy 0.5334 -0.254) (xy 0.635 -0.254) (xy 0.635 0.254) (xy 0.5334 0.254)
				(xy 0.5334 0.2794)
			)
			(stroke
				(width 0)
				(type default)
			)
			(fill no)
			(layer "F.CrtYd")
		)
		(pad "1" smd rect
			(at 0.40005 0 270)
			(size 0.4572 0.508)
			(layers "F.Cu" "F.Mask" "F.Paste")
			(net "PSU4_REMOTE_N")
		)
		(pad "2" smd rect
			(at -0.40005 0 270)
			(size 0.4572 0.508)
			(layers "F.Cu" "F.Mask" "F.Paste")
			(net "PSU4_REMOTE_R_N")
		)
	)
	(footprint ""
		(layer "F.Cu")
		(at 16.599916 -118.09984)
		(property "Reference" "H10"
			(at -7.888224 -6.127242 0)
			(unlocked yes)
			(layer "F.SilkS")
			(effects
				(font
					(size 0.7874 0.5842)
					(thickness 0.1524)
				)
				(justify left)
			)
		)
		(property "Value" ""
			(at 0 0 0)
			(layer "F.Fab")
			(effects
				(font
					(size 1.27 1.27)
				)
			)
		)
		(duplicate_pad_numbers_are_jumpers no)
		(fp_circle
			(center 0 0)
			(end 7.999984 0)
			(stroke
				(width 0.1524)
				(type default)
			)
			(fill no)
			(layer "F.SilkS")
		)
		(fp_circle
			(center 0 0)
			(end 14.7066 0)
			(stroke
				(width 0.1524)
				(type default)
			)
			(fill no)
			(layer "B.SilkS")
		)
		(fp_poly
			(pts
				(arc
					(start 0 5.0038)
					(mid 0 -5.0038)
					(end 0 5.0038)
				)
			)
			(stroke
				(width 0)
				(type default)
			)
			(fill no)
			(layer "F.CrtYd")
		)
		(pad "" np_thru_hole circle
			(at 0 0)
			(size 4.0132 4.0132)
			(drill 4.0132)
			(layers "*.Cu" "*.Mask")
			(clearance 0.381)
			(thermal_gap 0.381)
		)
		(pad "2" thru_hole circle
			(at 0 -3.50012)
			(size 0.762 0.762)
			(drill 0.5588)
			(layers "*.Cu" "*.Mask")
			(remove_unused_layers no)
			(net "GND")
			(clearance 0.1524)
			(thermal_gap 0.1524)
		)
		(pad "3" thru_hole circle
			(at -2.500122 -2.500122)
			(size 0.762 0.762)
			(drill 0.5588)
			(layers "*.Cu" "*.Mask")
			(remove_unused_layers no)
			(net "GND")
			(clearance 0.1524)
			(thermal_gap 0.1524)
		)
		(pad "4" thru_hole circle
			(at -3.50012 0)
			(size 0.762 0.762)
			(drill 0.5588)
			(layers "*.Cu" "*.Mask")
			(remove_unused_layers no)
			(net "GND")
			(clearance 0.1524)
			(thermal_gap 0.1524)
		)
		(pad "5" thru_hole circle
			(at -2.500122 2.500122)
			(size 0.762 0.762)
			(drill 0.5588)
			(layers "*.Cu" "*.Mask")
			(remove_unused_layers no)
			(net "GND")
			(clearance 0.1524)
			(thermal_gap 0.1524)
		)
		(pad "6" thru_hole circle
			(at 0 3.50012)
			(size 0.762 0.762)
			(drill 0.5588)
			(layers "*.Cu" "*.Mask")
			(remove_unused_layers no)
			(net "GND")
			(clearance 0.1524)
			(thermal_gap 0.1524)
		)
		(pad "7" thru_hole circle
			(at 2.500122 2.500122)
			(size 0.762 0.762)
			(drill 0.5588)
			(layers "*.Cu" "*.Mask")
			(remove_unused_layers no)
			(net "GND")
			(clearance 0.1524)
			(thermal_gap 0.1524)
		)
		(pad "8" thru_hole circle
			(at 3.50012 0)
			(size 0.762 0.762)
			(drill 0.5588)
			(layers "*.Cu" "*.Mask")
			(remove_unused_layers no)
			(net "GND")
			(clearance 0.1524)
			(thermal_gap 0.1524)
		)
		(pad "9" thru_hole circle
			(at 2.500122 -2.500122)
			(size 0.762 0.762)
			(drill 0.5588)
			(layers "*.Cu" "*.Mask")
			(remove_unused_layers no)
			(net "GND")
			(clearance 0.1524)
			(thermal_gap 0.1524)
		)
		(zone
			(layer "F.Cu")
			(hatch none 0.5)
			(connect_pads
				(clearance 0)
			)
			(min_thickness 0.25)
			(keepout
				(tracks not_allowed)
				(vias allowed)
				(pads allowed)
				(copperpour not_allowed)
				(footprints allowed)
			)
			(placement
				(enabled no)
				(sheetname "")
			)
			(fill
				(thermal_gap 0.5)
				(thermal_bridge_width 0.5)
				(island_removal_mode 0)
			)
			(polygon
				(pts
					(arc
						(start 16.599916 -126.10084)
						(mid 8.598916 -118.09984)
						(end 16.599916 -110.09884)
					)
					(arc
						(start 16.599916 -110.09884)
						(mid 18.035016 -111.53394)
						(end 16.599916 -112.96904)
					)
					(arc
						(start 16.599916 -112.96904)
						(mid 11.469116 -118.09984)
						(end 16.599916 -123.23064)
					)
					(arc
						(start 16.599916 -123.23064)
						(mid 18.035016 -124.66574)
						(end 16.599916 -126.10084)
					)
				)
			)
		)
		(zone
			(layer "F.Cu")
			(hatch none 0.5)
			(connect_pads
				(clearance 0)
			)
			(min_thickness 0.25)
			(keepout
				(tracks not_allowed)
				(vias allowed)
				(pads allowed)
				(copperpour not_allowed)
				(footprints allowed)
			)
			(placement
				(enabled no)
				(sheetname "")
			)
			(fill
				(thermal_gap 0.5)
				(thermal_bridge_width 0.5)
				(island_removal_mode 0)
			)
			(polygon
				(pts
					(arc
						(start 16.599916 -126.10084)
						(mid 24.600916 -118.09984)
						(end 16.599916 -110.09884)
					)
					(arc
						(start 16.599916 -110.09884)
						(mid 15.164816 -111.53394)
						(end 16.599916 -112.96904)
					)
					(arc
						(start 16.599916 -112.96904)
						(mid 21.730716 -118.09984)
						(end 16.599916 -123.23064)
					)
					(arc
						(start 16.599916 -123.23064)
						(mid 15.164816 -124.66574)
						(end 16.599916 -126.10084)
					)
				)
			)
		)
		(zone
			(layers "F.Cu" "B.Cu" "In1.Cu" "In2.Cu" "In3.Cu" "In4.Cu" "In5.Cu" "In6.Cu")
			(hatch none 0.5)
			(connect_pads
				(clearance 0)
			)
			(min_thickness 0.25)
			(keepout
				(tracks not_allowed)
				(vias allowed)
				(pads allowed)
				(copperpour not_allowed)
				(footprints allowed)
			)
			(placement
				(enabled no)
				(sheetname "")
			)
			(fill
				(thermal_gap 0.5)
				(thermal_bridge_width 0.5)
				(island_removal_mode 0)
			)
			(polygon
				(pts
					(arc
						(start 16.599916 -115.58778)
						(mid 16.599916 -120.6119)
						(end 16.599916 -115.58778)
					)
				)
			)
		)
	)
	(footprint ""
		(layer "F.Cu")
		(at 27.577796 -373.032528 90)
		(property "Reference" "R129"
			(at -3.094482 -0.932942 90)
			(unlocked yes)
			(layer "F.SilkS")
			(effects
				(font
					(size 0.7874 0.5842)
					(thickness 0.1524)
				)
				(justify left)
			)
		)
		(property "Value" ""
			(at 0 0 90)
			(layer "F.Fab")
			(effects
				(font
					(size 1.27 1.27)
				)
			)
		)
		(duplicate_pad_numbers_are_jumpers no)
		(fp_line
			(start 0.7874 -0.4064)
			(end 0.7874 0.4064)
			(stroke
				(width 0.1524)
				(type default)
			)
			(layer "F.SilkS")
		)
		(fp_line
			(start -0.7874 -0.4064)
			(end 0.7874 -0.4064)
			(stroke
				(width 0.1524)
				(type default)
			)
			(layer "F.SilkS")
		)
		(fp_line
			(start 0.7874 0.4064)
			(end -0.7874 0.4064)
			(stroke
				(width 0.1524)
				(type default)
			)
			(layer "F.SilkS")
		)
		(fp_line
			(start -0.7874 0.4064)
			(end -0.7874 -0.4064)
			(stroke
				(width 0.1524)
				(type default)
			)
			(layer "F.SilkS")
		)
		(fp_poly
			(pts
				(xy -0.508 0.2794) (xy -0.508 0.2286) (xy -0.635 0.2286) (xy -0.635 -0.254) (xy -0.5334 -0.254)
				(xy -0.5334 -0.2794) (xy 0.5334 -0.2794) (xy 0.5334 -0.254) (xy 0.635 -0.254) (xy 0.635 0.254) (xy 0.5334 0.254)
				(xy 0.5334 0.2794)
			)
			(stroke
				(width 0)
				(type default)
			)
			(fill no)
			(layer "F.CrtYd")
		)
		(pad "1" smd rect
			(at 0.40005 0 90)
			(size 0.4572 0.508)
			(layers "F.Cu" "F.Mask" "F.Paste")
			(net "PSU5_REMOTE_N")
		)
		(pad "2" smd rect
			(at -0.40005 0 90)
			(size 0.4572 0.508)
			(layers "F.Cu" "F.Mask" "F.Paste")
			(net "PSU5_REMOTE_R2_N")
		)
	)
	(footprint ""
		(layer "F.Cu")
		(at 74.832718 -259.450078 90)
		(property "Reference" "C46"
			(at -4.410456 0.239268 90)
			(unlocked yes)
			(layer "F.SilkS")
			(effects
				(font
					(size 0.7874 0.5842)
					(thickness 0.1524)
				)
				(justify left)
			)
		)
		(property "Value" ""
			(at 0 0 90)
			(layer "F.Fab")
			(effects
				(font
					(size 1.27 1.27)
				)
			)
		)
		(duplicate_pad_numbers_are_jumpers no)
		(fp_line
			(start 0.7874 -0.4064)
			(end 0.7874 0.4064)
			(stroke
				(width 0.1524)
				(type default)
			)
			(layer "F.SilkS")
		)
		(fp_line
			(start -0.7874 -0.4064)
			(end 0.7874 -0.4064)
			(stroke
				(width 0.1524)
				(type default)
			)
			(layer "F.SilkS")
		)
		(fp_line
			(start 0 0.381)
			(end 0 -0.381)
			(stroke
				(width 0.1524)
				(type default)
			)
			(layer "F.SilkS")
		)
		(fp_line
			(start 0.7874 0.4064)
			(end -0.7874 0.4064)
			(stroke
				(width 0.1524)
				(type default)
			)
			(layer "F.SilkS")
		)
		(fp_line
			(start -0.7874 0.4064)
			(end -0.7874 -0.4064)
			(stroke
				(width 0.1524)
				(type default)
			)
			(layer "F.SilkS")
		)
		(fp_poly
			(pts
				(xy -0.5334 0.254) (xy -0.635 0.254) (xy -0.635 0.2286) (xy -0.635 -0.254) (xy -0.5334 -0.254) (xy -0.5334 -0.2794)
				(xy 0.5334 -0.2794) (xy 0.5334 -0.254) (xy 0.635 -0.254) (xy 0.635 0.254) (xy 0.5334 0.254) (xy 0.5334 0.2794)
				(xy -0.508 0.2794) (xy -0.5334 0.2794)
			)
			(stroke
				(width 0)
				(type default)
			)
			(fill no)
			(layer "F.CrtYd")
		)
		(pad "1" smd rect
			(at 0.40005 0 90)
			(size 0.4572 0.508)
			(layers "F.Cu" "F.Mask" "F.Paste")
			(net "P12V")
		)
		(pad "2" smd rect
			(at -0.40005 0 90)
			(size 0.4572 0.508)
			(layers "F.Cu" "F.Mask" "F.Paste")
			(net "GND")
		)
	)
	(footprint ""
		(layer "F.Cu")
		(at 25.857708 -361.78236)
		(property "Reference" "R81"
			(at -3.917442 -0.225298 0)
			(unlocked yes)
			(layer "F.SilkS")
			(effects
				(font
					(size 0.7874 0.5842)
					(thickness 0.1524)
				)
				(justify left)
			)
		)
		(property "Value" ""
			(at 0 0 0)
			(layer "F.Fab")
			(effects
				(font
					(size 1.27 1.27)
				)
			)
		)
		(duplicate_pad_numbers_are_jumpers no)
		(fp_line
			(start -0.7874 -0.4064)
			(end 0.7874 -0.4064)
			(stroke
				(width 0.1524)
				(type default)
			)
			(layer "F.SilkS")
		)
		(fp_line
			(start -0.7874 0.4064)
			(end -0.7874 -0.4064)
			(stroke
				(width 0.1524)
				(type default)
			)
			(layer "F.SilkS")
		)
		(fp_line
			(start 0.7874 -0.4064)
			(end 0.7874 0.4064)
			(stroke
				(width 0.1524)
				(type default)
			)
			(layer "F.SilkS")
		)
		(fp_line
			(start 0.7874 0.4064)
			(end -0.7874 0.4064)
			(stroke
				(width 0.1524)
				(type default)
			)
			(layer "F.SilkS")
		)
		(fp_poly
			(pts
				(xy -0.508 0.2794) (xy -0.508 0.2286) (xy -0.635 0.2286) (xy -0.635 -0.254) (xy -0.5334 -0.254)
				(xy -0.5334 -0.2794) (xy 0.5334 -0.2794) (xy 0.5334 -0.254) (xy 0.635 -0.254) (xy 0.635 0.254) (xy 0.5334 0.254)
				(xy 0.5334 0.2794)
			)
			(stroke
				(width 0)
				(type default)
			)
			(fill no)
			(layer "F.CrtYd")
		)
		(pad "1" smd rect
			(at 0.40005 0)
			(size 0.4572 0.508)
			(layers "F.Cu" "F.Mask" "F.Paste")
			(net "PSU5_RESET")
		)
		(pad "2" smd rect
			(at -0.40005 0)
			(size 0.4572 0.508)
			(layers "F.Cu" "F.Mask" "F.Paste")
			(net "GND")
		)
	)
)
